# TIMECARD (Time Appliance Project (Time Card)) — schematic netlist excerpt (pin names and nets, part order shuffled) for the footprints in the layout excerpt that follows; sources: Cadence DE-HDL packaged netlist, KiCad conversion of R4006-B0001-02_R01.brd

R248  RESISTOR  100KOHM 1%  pkg SMC_0402R_H016  page 29 : \1\ = XP1R0V_RT ; \2\ = XP1R0V_AGND
TP8  TP_PIONT  pkg TP010CT020B030_PTH  page 24 : \1\ = UNNAMED_524_FT4232HLREELQFP64_3
SP34  SOLDER_PREFORM  pkg 0201_SOLDER_PREFORM_4MIL  page 34 : \1\ = NC ; \2\ = NC

(kicad_pcb
	(version 20260206)
	(generator "pcbnew")
	(generator_version "10.0")
	(general
		(thickness 1.6)
		(legacy_teardrops no)
	)
	(paper "A4")
	(title_block
		(title "timecard-production-celestica-r4006 — R4006-B0001-02_R01.brd")
		(comment 1 "Time Appliance Project (Time Card) / footprints 22-24 of 1113")
	)
	(layers
		(0 "F.Cu" signal "TOP")
		(4 "In1.Cu" signal "L02_GND1")
		(6 "In2.Cu" signal "L03_SIG1")
		(8 "In3.Cu" signal "L04_GND2")
		(10 "In4.Cu" signal "L05_VCC1")
		(12 "In5.Cu" signal "L06_VCC2")
		(14 "In6.Cu" signal "L07_GND3")
		(16 "In7.Cu" signal "L08_SIG2")
		(18 "In8.Cu" signal "L09_GND4")
		(2 "B.Cu" signal "BOTTOM")
		(9 "F.Adhes" user "F.Adhesive")
		(11 "B.Adhes" user "B.Adhesive")
		(13 "F.Paste" user "Package Geometry/Pastemask Top")
		(15 "B.Paste" user "Package Geometry/Pastemask Bottom")
		(5 "F.SilkS" user "Ref Des/Silkscreen Top")
		(7 "B.SilkS" user "Ref Des/Silkscreen Bottom")
		(1 "F.Mask" user "Board Geometry/Soldermask Top")
		(3 "B.Mask" user "Board Geometry/Soldermask Bottom")
		(17 "Dwgs.User" user "User.Drawings")
		(19 "Cmts.User" user "User.Comments")
		(21 "Eco1.User" user "User.Eco1")
		(23 "Eco2.User" user "User.Eco2")
		(25 "Edge.Cuts" user "Board Geometry/Outline")
		(27 "Margin" user)
		(31 "F.CrtYd" user "Package Geometry/Place Bound Top")
		(29 "B.CrtYd" user "Package Geometry/Place Bound Bottom")
		(35 "F.Fab" user "Ref Des/Assembly Top")
		(33 "B.Fab" user "Ref Des/Assembly Bottom")
	)
	(footprint ""
		(layer "F.Cu")
		(at 22.479 -76.962 90)
		(property "Reference" "TP8"
			(at 0 0 90)
			(layer "F.SilkS")
			(hide yes)
			(effects
				(font
					(size 1.27 1.27)
				)
			)
		)
		(property "Value" ""
			(at 0 0 90)
			(layer "F.Fab")
			(effects
				(font
					(size 1.27 1.27)
				)
			)
		)
		(property "Device Type" "TP_PIONT-TP010CT020B030_PTH-TPA"
			(at -1.341882 0.996696 90)
			(unlocked yes)
			(layer "F.Fab")
			(hide yes)
			(effects
				(font
					(size 0.7874 0.5842)
					(thickness 0.1524)
				)
				(justify left)
			)
		)
		(duplicate_pad_numbers_are_jumpers no)
		(fp_poly
			(pts
				(arc
					(start 0 0.889)
					(mid 0 -0.889)
					(end 0 0.889)
				)
			)
			(stroke
				(width 0)
				(type default)
			)
			(fill no)
			(layer "B.CrtYd")
		)
		(fp_poly
			(pts
				(arc
					(start 0 0.889)
					(mid 0 -0.889)
					(end 0 0.889)
				)
			)
			(stroke
				(width 0)
				(type default)
			)
			(fill no)
			(layer "F.CrtYd")
		)
		(pad "1" thru_hole circle
			(at 0 0 90)
			(size 0.508 0.508)
			(drill 0.254)
			(layers "*.Cu" "*.Mask")
			(remove_unused_layers no)
			(net "UNNAMED_524_FT4232HLREELQFP64_3")
			(clearance 0.1016)
			(padstack
				(mode front_inner_back)
				(layer "Inner"
					(shape circle)
					(size 0.508 0.508)
					(clearance 0.1016)
				)
				(layer "B.Cu"
					(shape circle)
					(size 0.762 0.762)
					(clearance -0.0254)
				)
			)
		)
	)
	(footprint ""
		(layer "F.Cu")
		(at 43.942 -126.111)
		(property "Reference" "SP34"
			(at 0 0 0)
			(layer "F.SilkS")
			(hide yes)
			(effects
				(font
					(size 1.27 1.27)
				)
			)
		)
		(property "Value" ""
			(at 0 0 0)
			(layer "F.Fab")
			(effects
				(font
					(size 1.27 1.27)
				)
			)
		)
		(duplicate_pad_numbers_are_jumpers no)
	)
	(footprint ""
		(layer "F.Cu")
		(at 146.05 -57.023)
		(property "Reference" "R248"
			(at 2.794 2.32537 0)
			(unlocked yes)
			(layer "F.SilkS")
			(effects
				(font
					(size 0.7874 0.5842)
					(thickness 0.1524)
				)
			)
		)
		(property "Value" "VAL*"
			(at 0.02032 2.13233 0)
			(unlocked yes)
			(layer "F.Fab")
			(hide yes)
			(effects
				(font
					(size 0.7874 0.5842)
					(thickness 0.1524)
				)
			)
		)
		(property "Device Type" "RESISTOR-G155-11003-01,100KOHMA"
			(at 0.008382 1.210564 0)
			(unlocked yes)
			(layer "F.Fab")
			(hide yes)
			(effects
				(font
					(size 0.7874 0.5842)
					(thickness 0.1524)
				)
			)
		)
		(property "User Part Number" "PARTNUM*"
			(at 0.02032 4.024884 0)
			(unlocked yes)
			(layer "Cmts.User")
			(hide yes)
			(effects
				(font
					(size 0.7874 0.5842)
					(thickness 0.1524)
				)
			)
		)
		(property "Tolerance" "TOL*"
			(at 0.044704 3.05435 0)
			(unlocked yes)
			(layer "Cmts.User")
			(hide yes)
			(effects
				(font
					(size 0.7874 0.5842)
					(thickness 0.1524)
				)
			)
		)
		(duplicate_pad_numbers_are_jumpers no)
		(fp_line
			(start -1.143 -0.5588)
			(end -1.143 0.5588)
			(stroke
				(width 0.1)
				(type default)
			)
			(layer "F.SilkS")
		)
		(fp_line
			(start -1.143 0.5588)
			(end 1.143 0.5588)
			(stroke
				(width 0.1)
				(type default)
			)
			(layer "F.SilkS")
		)
		(fp_line
			(start 1.143 -0.5588)
			(end -1.143 -0.5588)
			(stroke
				(width 0.1)
				(type default)
			)
			(layer "F.SilkS")
		)
		(fp_line
			(start 1.143 0.5588)
			(end 1.143 -0.5588)
			(stroke
				(width 0.1)
				(type default)
			)
			(layer "F.SilkS")
		)
		(fp_rect
			(start -1.143 0.5588)
			(end 1.143 -0.5588)
			(stroke
				(width 0)
				(type default)
			)
			(fill no)
			(layer "F.CrtYd")
		)
		(fp_line
			(start -0.508 -0.3048)
			(end -0.508 0.3048)
			(stroke
				(width 0.1)
				(type default)
			)
			(layer "F.Fab")
		)
		(fp_line
			(start -0.508 0.3048)
			(end 0.508 0.3048)
			(stroke
				(width 0.1)
				(type default)
			)
			(layer "F.Fab")
		)
		(fp_line
			(start 0.508 -0.3048)
			(end -0.508 -0.3048)
			(stroke
				(width 0.1)
				(type default)
			)
			(layer "F.Fab")
		)
		(fp_line
			(start 0.508 0.3048)
			(end 0.508 -0.3048)
			(stroke
				(width 0.1)
				(type default)
			)
			(layer "F.Fab")
		)
		(pad "1" smd rect
			(at -0.5334 0)
			(size 0.7112 0.6096)
			(layers "F.Cu" "F.Mask" "F.Paste")
			(net "XP1R0V_RT")
		)
		(pad "2" smd rect
			(at 0.5334 0)
			(size 0.7112 0.6096)
			(layers "F.Cu" "F.Mask" "F.Paste")
			(net "XP1R0V_AGND")
		)
		(zone
			(layer "F.Cu")
			(hatch none 0.5)
			(connect_pads
				(clearance 0)
			)
			(min_thickness 0.25)
			(keepout
				(tracks allowed)
				(vias not_allowed)
				(pads allowed)
				(copperpour not_allowed)
				(footprints allowed)
			)
			(placement
				(enabled no)
				(sheetname "")
			)
			(fill
				(thermal_gap 0.5)
				(thermal_bridge_width 0.5)
				(island_removal_mode 0)
			)
			(polygon
				(pts
					(xy 145.9738 -56.7182) (xy 146.1262 -56.7182) (xy 146.1262 -57.3278) (xy 145.9738 -57.3278)
				)
			)
		)
	)
)
